# S9S_MB_2U (Grand Teton) — schematic parts with pin connectivity, parts 1613–1613 of 6093; source: Cadence DE-HDL packaged netlist (pstxprt.dat, pstxnet.dat, pstchip.dat)

J20  SCONN288_ADR50017P087CC  SCONN288_ADR50017-P087CC IO  pkg DDR288S_1-1VXB  page 101
  1  VIN_BULK0  POWER  = P12V_S3_AUX_CPU1_NVDIMM
  2  RFU0  TRI  = TP_CHB_CPU1_DIMM2_FRU_0
  3  VIN_MGMT  POWER  = P3V3_AUX
  4  HSCL  IN  = I3C_SPD_DDRABCD_CPU1_LVC1_SCL_3
  5  HSDA  BI  = I3C_SPD_DDRABCD_CPU1_LVC1_SDA
  6  VSS0  POWER  = GND
  7  DQ0_A  BI  = M_B_CPU1_SA_DQ<0>
  8  VSS1  POWER  = GND
  9  DQ1_A  BI  = M_B_CPU1_SA_DQ<1>
  10  VSS2  POWER  = GND
  11  DQS0_A_T  BI  = M_B_CPU1_SA_DQS_DP<0>
  12  DQS0_A_C  BI  = M_B_CPU1_SA_DQS_DN<0>
  13  VSS3  POWER  = GND
  14  DQ4_A  BI  = M_B_CPU1_SA_DQ<4>
  15  VSS4  POWER  = GND
  16  DQ5_A  BI  = M_B_CPU1_SA_DQ<5>
  17  VSS5  POWER  = GND
  18  DQ8_A  BI  = M_B_CPU1_SA_DQ<8>
  19  VSS6  POWER  = GND
  20  DQ9_A  BI  = M_B_CPU1_SA_DQ<9>
  21  VSS7  POWER  = GND
  22  DQS1_A_T  BI  = M_B_CPU1_SA_DQS_DP<1>
  23  DQS1_A_C  BI  = M_B_CPU1_SA_DQS_DN<1>
  24  VSS8  POWER  = GND
  25  DQ12_A  BI  = M_B_CPU1_SA_DQ<12>
  26  VSS9  POWER  = GND
  27  DQ13_A  BI  = M_B_CPU1_SA_DQ<13>
  28  VSS10  POWER  = GND
  29  DQ16_A  BI  = M_B_CPU1_SA_DQ<16>
  30  VSS11  POWER  = GND
  31  DQ17_A  BI  = M_B_CPU1_SA_DQ<17>
  32  VSS12  POWER  = GND
  33  DQS2_A_T  BI  = M_B_CPU1_SA_DQS_DP<2>
  34  DQS2_A_C  BI  = M_B_CPU1_SA_DQS_DN<2>
  35  VSS13  POWER  = GND
  36  DQ20_A  BI  = M_B_CPU1_SA_DQ<20>
  37  VSS14  POWER  = GND
  38  DQ21_A  BI  = M_B_CPU1_SA_DQ<21>
  39  VSS15  POWER  = GND
  40  DQ24_A  BI  = M_B_CPU1_SA_DQ<24>
  41  VSS16  POWER  = GND
  42  DQ25_A  BI  = M_B_CPU1_SA_DQ<25>
  43  VSS17  POWER  = GND
  44  DQS3_A_T  BI  = M_B_CPU1_SA_DQS_DP<3>
  45  DQS3_A_C  BI  = M_B_CPU1_SA_DQS_DN<3>
  46  VSS18  POWER  = GND
  47  DQ28_A  BI  = M_B_CPU1_SA_DQ<28>
  48  VSS19  POWER  = GND
  49  DQ29_A  BI  = M_B_CPU1_SA_DQ<29>
  50  VSS20  POWER  = GND
  51  CB0_A  BI  = M_B_CPU1_SA_CB<0>
  52  VSS21  POWER  = GND
  53  CB1_A  BI  = M_B_CPU1_SA_CB<1>
  54  VSS22  POWER  = GND
  55  DQS4_A_T  BI  = M_B_CPU1_SA_DQS_DP<4>
  56  DQS4_A_C  BI  = M_B_CPU1_SA_DQS_DN<4>
  57  VSS23  POWER  = GND
  58  CB4_A  BI  = M_B_CPU1_SA_CB<4>
  59  VSS24  POWER  = GND
  60  CB5_A  BI  = M_B_CPU1_SA_CB<5>
  61  VSS25  POWER  = GND
  62  ALERT_N  OUT  = M_B_CPU1_ALERT_N
  63  VSS26  POWER  = GND
  64  CS0_A_N  IN  = M_B_CPU1_SA_CS_N<2>
  65  VSS27  POWER  = GND
  66  CA0_A  IN  = M_B_CPU1_SA_CA<0>
  67  VSS28  POWER  = GND
  68  CA2_A  IN  = M_B_CPU1_SA_CA<2>
  69  VSS29  POWER  = GND
  70  CA4_A  IN  = M_B_CPU1_SA_CA<4>
  71  VSS30  POWER  = GND
  72  CA6_A  IN  = M_B_CPU1_SA_CA<6>
  73  VSS31  POWER  = GND
  74  PAR_A  IN  = M_B_CPU1_SA_PAR
  75  VSS32  POWER  = GND
  76  CA0_B  IN  = M_B_CPU1_SB_CA<0>
  77  VSS33  POWER  = GND
  78  CA2_B  IN  = M_B_CPU1_SB_CA<2>
  79  VSS34  POWER  = GND
  80  CA4_B  IN  = M_B_CPU1_SB_CA<4>
  81  VSS35  POWER  = GND
  82  CA6_B  IN  = M_B_CPU1_SB_CA<6>
  83  VSS36  POWER  = GND
  84  CS0_B_N  IN  = M_B_CPU1_SB_CS_N<2>
  85  VSS37  POWER  = GND
  86  \lbd||rsp_a_n\  OUT  = M_B_CPU1_SA_RSP<1>
  87  \lbs||rsp_b_n\  OUT  = M_B_CPU1_SB_RSP<1>
  88  VSS38  POWER  = GND
  89  CB4_B  BI  = M_B_CPU1_SB_CB<4>
  90  VSS39  POWER  = GND
  91  CB5_B  BI  = M_B_CPU1_SB_CB<5>
  92  VSS40  POWER  = GND
  93  \dqs9_b_t||tdqs9_b_t||dbi4_b_n\  BI  = M_B_CPU1_SB_DQS_DP<9>
  94  \dqs9_b_c||tdqs9_b_c\  BI  = M_B_CPU1_SB_DQS_DN<9>
  95  VSS41  POWER  = GND
  96  CB0_B  BI  = M_B_CPU1_SB_CB<0>
  97  VSS42  POWER  = GND
  98  CB1_B  BI  = M_B_CPU1_SB_CB<1>
  99  VSS43  POWER  = GND
  100  DQ0_B  BI  = M_B_CPU1_SB_DQ<0>
  101  VSS44  POWER  = GND
  102  DQ1_B  BI  = M_B_CPU1_SB_DQ<1>
  103  VSS45  POWER  = GND
  104  DQS0_B_T  BI  = M_B_CPU1_SB_DQS_DP<0>
  105  DQS0_B_C  BI  = M_B_CPU1_SB_DQS_DN<0>
  106  VSS46  POWER  = GND
  107  DQ4_B  BI  = M_B_CPU1_SB_DQ<4>
  108  VSS47  POWER  = GND
  109  DQ5_B  BI  = M_B_CPU1_SB_DQ<5>
  110  VSS48  POWER  = GND
  111  DQ8_B  BI  = M_B_CPU1_SB_DQ<8>
  112  VSS49  POWER  = GND
  113  DQ9_B  BI  = M_B_CPU1_SB_DQ<9>
  114  VSS50  POWER  = GND
  115  DQS1_B_T  BI  = M_B_CPU1_SB_DQS_DP<1>
  116  DQS1_B_C  BI  = M_B_CPU1_SB_DQS_DN<1>
  117  VSS51  POWER  = GND
  118  DQ12_B  BI  = M_B_CPU1_SB_DQ<12>
  119  VSS52  POWER  = GND
  120  DQ13_B  BI  = M_B_CPU1_SB_DQ<13>
  121  VSS53  POWER  = GND
  122  DQ16_B  BI  = M_B_CPU1_SB_DQ<16>
  123  VSS54  POWER  = GND
  124  DQ17_B  BI  = M_B_CPU1_SB_DQ<17>
  125  VSS55  POWER  = GND
  126  DQS2_B_T  BI  = M_B_CPU1_SB_DQS_DP<2>
  127  DQS2_B_C  BI  = M_B_CPU1_SB_DQS_DN<2>
  128  VSS56  POWER  = GND
  129  DQ20_B  BI  = M_B_CPU1_SB_DQ<20>
  130  VSS57  POWER  = GND
  131  DQ21_B  BI  = M_B_CPU1_SB_DQ<21>
  132  VSS58  POWER  = GND
  133  DQ24_B  BI  = M_B_CPU1_SB_DQ<24>
  134  VSS59  POWER  = GND
  135  DQ25_B  BI  = M_B_CPU1_SB_DQ<25>
  136  VSS60  POWER  = GND
  137  DQS3_B_T  BI  = M_B_CPU1_SB_DQS_DP<3>
  138  DQS3_B_C  BI  = M_B_CPU1_SB_DQS_DN<3>
  139  VSS61  POWER  = GND
  140  DQ28_B  BI  = M_B_CPU1_SB_DQ<28>
  141  VSS62  POWER  = GND
  142  DQ29_B  BI  = M_B_CPU1_SB_DQ<29>
  143  VSS63  POWER  = GND
  144  RFU1  TRI  = TP_CHB_CPU1_DIMM2_FRU_1
  145  VIN_BULK1  POWER  = P12V_S3_AUX_CPU1_NVDIMM
  146  VIN_BULK2  POWER  = P12V_S3_AUX_CPU1_NVDIMM
  147  \pwr_good||fail_n\  BI  = PWRGD_CHB_CPU1_DIMM2
  148  HSA  IN  = PD_CHB_CPU1_DIMM2_SAA
  149  RFU2  TRI  = TP_CHB_CPU1_DIMM2_FRU_2
  150  RFU3  TRI  = TP_CHB_CPU1_DIMM2_FRU_3
  151  VSS64  POWER  = GND
  152  DQ2_A  BI  = M_B_CPU1_SA_DQ<2>
  153  VSS65  POWER  = GND
  154  DQ3_A  BI  = M_B_CPU1_SA_DQ<3>
  155  VSS66  POWER  = GND
  156  \dqs5_a_c||tdqs5_a_c||dqs5_a_t||tdqs5_a_t\  BI  = M_B_CPU1_SA_DQS_DN<5>
  157  \dqs5_a_t||tdqs5_a_t\  BI  = M_B_CPU1_SA_DQS_DP<5>
  158  VSS67  POWER  = GND
  159  DQ6_A  BI  = M_B_CPU1_SA_DQ<6>
  160  VSS68  POWER  = GND
  161  DQ7_A  BI  = M_B_CPU1_SA_DQ<7>
  162  VSS69  POWER  = GND
  163  DQ10_A  BI  = M_B_CPU1_SA_DQ<10>
  164  VSS70  POWER  = GND
  165  DQ11_A  BI  = M_B_CPU1_SA_DQ<11>
  166  VSS71  POWER  = GND
  167  \dqs6_a_c||tdqs6_a_c||dqs6_a_t||tdqs6_a_t\  BI  = M_B_CPU1_SA_DQS_DN<6>
  168  \dqs6_a_t||tdqs6_a_t\  BI  = M_B_CPU1_SA_DQS_DP<6>
  169  VSS72  POWER  = GND
  170  DQ14_A  BI  = M_B_CPU1_SA_DQ<14>
  171  VSS73  POWER  = GND
  172  DQ15_A  BI  = M_B_CPU1_SA_DQ<15>
  173  VSS74  POWER  = GND
  174  DQ18_A  BI  = M_B_CPU1_SA_DQ<18>
  175  VSS75  POWER  = GND
  176  DQ19_A  BI  = M_B_CPU1_SA_DQ<19>
  177  VSS76  POWER  = GND
  178  \dqs7_a_c||tdqs7_a_c\  BI  = M_B_CPU1_SA_DQS_DN<7>
  179  \dqs7_a_t||tdqs7_a_t\  BI  = M_B_CPU1_SA_DQS_DP<7>
  180  VSS77  POWER  = GND
  181  DQ22_A  BI  = M_B_CPU1_SA_DQ<22>
  182  VSS78  POWER  = GND
  183  DQ23_A  BI  = M_B_CPU1_SA_DQ<23>
  184  VSS79  POWER  = GND
  185  DQ26_A  BI  = M_B_CPU1_SA_DQ<26>
  186  VSS80  POWER  = GND
  187  DQ27_A  BI  = M_B_CPU1_SA_DQ<27>
  188  VSS81  POWER  = GND
  189  \dqs8_a_c||tdqs8_a_c\  BI  = M_B_CPU1_SA_DQS_DN<8>
  190  \dqs8_a_t||tdqs8_a_t\  BI  = M_B_CPU1_SA_DQS_DP<8>
  191  VSS82  POWER  = GND
  192  DQ30_A  BI  = M_B_CPU1_SA_DQ<30>
  193  VSS83  POWER  = GND
  194  DQ31_A  BI  = M_B_CPU1_SA_DQ<31>
  195  VSS84  POWER  = GND
  196  CB2_A  BI  = M_B_CPU1_SA_CB<2>
  197  VSS85  POWER  = GND
  198  CB3_A  BI  = M_B_CPU1_SA_CB<3>
  199  VSS86  POWER  = GND
  200  \dqs9_a_c||tdqs9_a_c\  BI  = M_B_CPU1_SA_DQS_DN<9>
  201  \dqs9_a_t||tdqs9_a_t\  BI  = M_B_CPU1_SA_DQS_DP<9>
  202  VSS87  POWER  = GND
  203  CB6_A  BI  = M_B_CPU1_SA_CB<6>
  204  VSS88  POWER  = GND
  205  CB7_A  BI  = M_B_CPU1_SA_CB<7>
  206  VSS89  POWER  = GND
  207  RESET_N  IN  = RST_M_AB_CPU1_FPGA_N
  208  VSS90  POWER  = GND
  209  CS1_A_N  IN  = M_B_CPU1_SA_CS_N<3>
  210  VSS91  POWER  = GND
  211  CA1_A  IN  = M_B_CPU1_SA_CA<1>
  212  VSS92  POWER  = GND
  213  CA3_A  IN  = M_B_CPU1_SA_CA<3>
  214  VSS93  POWER  = GND
  215  CA5_A  IN  = M_B_CPU1_SA_CA<5>
  216  VSS94  POWER  = GND
  217  CK_T  IN  = M_B_CPU1_CLK_DP<1>
  218  CK_C  IN  = M_B_CPU1_CLK_DN<1>
  219  VSS95  POWER  = GND
  220  RFU4  TRI  = TP_CHB_CPU1_DIMM2_FRU_4
  221  CA1_B  IN  = M_B_CPU1_SB_CA<1>
  222  VSS96  POWER  = GND
  223  CA3_B  IN  = M_B_CPU1_SB_CA<3>
  224  VSS97  POWER  = GND
  225  CA5_B  IN  = M_B_CPU1_SB_CA<5>
  226  VSS98  POWER  = GND
  227  PAR_B  IN  = M_B_CPU1_SB_PAR
  228  VSS99  POWER  = GND
  229  CS1_B_N  IN  = M_B_CPU1_SB_CS_N<3>
  230  VSS100  POWER  = GND
  231  RFU5  TRI  = TP_CHB_CPU1_DIMM2_FRU_5
  232  RFU6  TRI  = TP_CHB_CPU1_DIMM2_FRU_6
  233  VSS101  POWER  = GND
  234  CB6_B  BI  = M_B_CPU1_SB_CB<6>
  235  VSS102  POWER  = GND
  236  CB7_B  BI  = M_B_CPU1_SB_CB<7>
  237  VSS103  POWER  = GND
  238  DQS4_B_C  BI  = M_B_CPU1_SB_DQS_DN<4>
  239  DQS4_B_T  BI  = M_B_CPU1_SB_DQS_DP<4>
  240  VSS104  POWER  = GND
  241  CB2_B  BI  = M_B_CPU1_SB_CB<2>
  242  VSS105  POWER  = GND
  243  CB3_B  BI  = M_B_CPU1_SB_CB<3>
  244  VSS106  POWER  = GND
  245  DQ2_B  BI  = M_B_CPU1_SB_DQ<2>
  246  VSS107  POWER  = GND
  247  DQ3_B  BI  = M_B_CPU1_SB_DQ<3>
  248  VSS108  POWER  = GND
  249  \dqs5_b_c||tdqs5_b_c\  BI  = M_B_CPU1_SB_DQS_DN<5>
  250  \dqs5_b_t||tdqs5_b_t\  BI  = M_B_CPU1_SB_DQS_DP<5>
  251  VSS109  POWER  = GND
  252  DQ6_B  BI  = M_B_CPU1_SB_DQ<6>
  253  VSS110  POWER  = GND
  254  DQ7_B  BI  = M_B_CPU1_SB_DQ<7>
  255  VSS111  POWER  = GND
  256  DQ10_B  BI  = M_B_CPU1_SB_DQ<10>
  257  VSS112  POWER  = GND
  258  DQ11_B  BI  = M_B_CPU1_SB_DQ<11>
  259  VSS113  POWER  = GND
  260  \dqs6_b_c||tdqs6_b_c\  BI  = M_B_CPU1_SB_DQS_DN<6>
  261  \dqs6_b_t||tdqs6_b_t\  BI  = M_B_CPU1_SB_DQS_DP<6>
  262  VSS114  POWER  = GND
  263  DQ14_B  BI  = M_B_CPU1_SB_DQ<14>
  264  VSS115  POWER  = GND
  265  DQ15_B  BI  = M_B_CPU1_SB_DQ<15>
  266  VSS116  POWER  = GND
  267  DQ18_B  BI  = M_B_CPU1_SB_DQ<18>
  268  VSS117  POWER  = GND
  269  DQ19_B  BI  = M_B_CPU1_SB_DQ<19>
  270  VSS118  POWER  = GND
  271  \dqs7_b_c||tdqs7_b_c\  BI  = M_B_CPU1_SB_DQS_DN<7>
  272  \dqs7_b_t||tdqs7_b_t\  BI  = M_B_CPU1_SB_DQS_DP<7>
  273  VSS119  POWER  = GND
  274  DQ22_B  BI  = M_B_CPU1_SB_DQ<22>
  275  VSS120  POWER  = GND
  276  DQ23_B  BI  = M_B_CPU1_SB_DQ<23>
  277  VSS121  POWER  = GND
  278  DQ26_B  BI  = M_B_CPU1_SB_DQ<26>
  279  VSS122  POWER  = GND
  280  DQ27_B  BI  = M_B_CPU1_SB_DQ<27>
  281  VSS123  POWER  = GND
  282  \dqs8_b_c||tdqs8_b_c\  BI  = M_B_CPU1_SB_DQS_DN<8>
  283  \dqs8_b_t||tdqs8_b_t\  BI  = M_B_CPU1_SB_DQS_DP<8>
  284  VSS124  POWER  = GND
  285  DQ30_B  BI  = M_B_CPU1_SB_DQ<30>
  286  VSS125  POWER  = GND
  287  DQ31_B  BI  = M_B_CPU1_SB_DQ<31>
  288  VSS126  POWER  = GND
  G1  G1  POWER  = GND
  G2  G2  POWER  = GND
  G3  G3  POWER  = GND
